(kicad_pcb
	(version 20260206)
	(generator "pcbnew")
	(generator_version "10.0")
	(general
		(thickness 1.6)
		(legacy_teardrops no)
	)
	(paper "A4")
	(title_block
		(title "pdpb — Lightning_PDPB_BRD.brd")
		(comment 1 "Lightning (Wiwynn / Facebook NVMe JBOF) / footprints 429-435 of 1140")
	)
	(layers
		(0 "F.Cu" signal "TOP")
		(4 "In1.Cu" signal "L2GND")
		(6 "In2.Cu" signal "L3")
		(8 "In3.Cu" signal "L4VCC")
		(10 "In4.Cu" signal "L5VCC")
		(12 "In5.Cu" signal "L6")
		(14 "In6.Cu" signal "L7GND")
		(2 "B.Cu" signal "BOTTOM")
		(9 "F.Adhes" user "F.Adhesive")
		(11 "B.Adhes" user "B.Adhesive")
		(13 "F.Paste" user "Package Geometry/Pastemask Top")
		(15 "B.Paste" user "Package Geometry/Pastemask Bottom")
		(5 "F.SilkS" user "Ref Des/Silkscreen Top")
		(7 "B.SilkS" user "Ref Des/Silkscreen Bottom")
		(1 "F.Mask" user "Board Geometry/Soldermask Top")
		(3 "B.Mask" user "Board Geometry/Soldermask Bottom")
		(17 "Dwgs.User" user "User.Drawings")
		(19 "Cmts.User" user "User.Comments")
		(21 "Eco1.User" user "User.Eco1")
		(23 "Eco2.User" user "User.Eco2")
		(25 "Edge.Cuts" user "Board Geometry/Outline")
		(27 "Margin" user)
		(31 "F.CrtYd" user "Package Geometry/Place Bound Top")
		(29 "B.CrtYd" user "Package Geometry/Place Bound Bottom")
		(35 "F.Fab" user "Ref Des/Assembly Top")
		(33 "B.Fab" user "Ref Des/Assembly Bottom")
	)
	(footprint ""
		(layer "F.Cu")
		(at 203.454 -460.248 90)
		(property "Reference" "R314"
			(at 0 0 90)
			(layer "F.SilkS")
			(hide yes)
			(effects
				(font
					(size 1.27 1.27)
				)
			)
		)
		(property "Value" "0R2J-2-GP"
			(at 0.064008 -3.993896 90)
			(unlocked yes)
			(layer "F.Fab")
			(hide yes)
			(effects
				(font
					(size 1.016 1.016)
					(thickness 0.1524)
				)
			)
		)
		(property "Device Type" "R402H16"
			(at 0.064008 -5.517896 90)
			(unlocked yes)
			(layer "F.Fab")
			(hide yes)
			(effects
				(font
					(size 1.016 1.016)
					(thickness 0.1524)
				)
			)
		)
		(duplicate_pad_numbers_are_jumpers no)
		(fp_line
			(start 0.508 -0.9398)
			(end -0.508 -0.9398)
			(stroke
				(width 0.1524)
				(type default)
			)
			(layer "F.SilkS")
		)
		(fp_line
			(start -0.508 -0.9398)
			(end -0.508 0.9398)
			(stroke
				(width 0.1524)
				(type default)
			)
			(layer "F.SilkS")
		)
		(fp_rect
			(start -0.508 0.9398)
			(end 0.508 -0.9398)
			(stroke
				(width 0)
				(type default)
			)
			(fill no)
			(layer "F.CrtYd")
		)
		(fp_rect
			(start -0.508 0.9398)
			(end 0.508 -0.9398)
			(stroke
				(width 0)
				(type default)
			)
			(fill no)
			(layer "F.Fab")
		)
		(pad "1" smd custom
			(at 0 -0.4445 90)
			(size 0.1397 0.1397)
			(layers "F.Cu" "F.Mask" "F.Paste")
			(net "I2C_B_SDA")
			(options
				(clearance outline)
				(anchor circle)
			)
			(primitives
				(gr_poly
					(pts
						(arc
							(start -0.1778 -0.2794)
							(mid -0.249642 -0.249642)
							(end -0.2794 -0.1778)
						)
						(arc
							(start -0.2794 0.1778)
							(mid -0.249642 0.249642)
							(end -0.1778 0.2794)
						)
						(arc
							(start 0.1778 0.2794)
							(mid 0.249642 0.249642)
							(end 0.2794 0.1778)
						)
						(arc
							(start 0.2794 -0.1778)
							(mid 0.249642 -0.249642)
							(end 0.1778 -0.2794)
						)
					)
					(width 0)
					(fill yes)
				)
			)
		)
		(pad "2" smd custom
			(at 0 0.4445 90)
			(size 0.1397 0.1397)
			(layers "F.Cu" "F.Mask" "F.Paste")
			(net "TMP2_SDA")
			(options
				(clearance outline)
				(anchor circle)
			)
			(primitives
				(gr_poly
					(pts
						(arc
							(start -0.1778 -0.2794)
							(mid -0.249642 -0.249642)
							(end -0.2794 -0.1778)
						)
						(arc
							(start -0.2794 0.1778)
							(mid -0.249642 0.249642)
							(end -0.1778 0.2794)
						)
						(arc
							(start 0.1778 0.2794)
							(mid 0.249642 0.249642)
							(end 0.2794 0.1778)
						)
						(arc
							(start 0.2794 -0.1778)
							(mid 0.249642 -0.249642)
							(end 0.1778 -0.2794)
						)
					)
					(width 0)
					(fill yes)
				)
			)
		)
	)
	(footprint ""
		(layer "F.Cu")
		(at 95.504 -219.456 180)
		(property "Reference" "R9096"
			(at 0 0 180)
			(layer "F.SilkS")
			(hide yes)
			(effects
				(font
					(size 1.27 1.27)
				)
			)
		)
		(property "Value" "27R2F-GP"
			(at 0.064008 -3.993896 180)
			(unlocked yes)
			(layer "F.Fab")
			(hide yes)
			(effects
				(font
					(size 1.016 1.016)
					(thickness 0.1524)
				)
			)
		)
		(property "Device Type" "R402H16"
			(at 0.064008 -5.517896 180)
			(unlocked yes)
			(layer "F.Fab")
			(hide yes)
			(effects
				(font
					(size 1.016 1.016)
					(thickness 0.1524)
				)
			)
		)
		(duplicate_pad_numbers_are_jumpers no)
		(fp_line
			(start 0.508 -0.9398)
			(end -0.508 -0.9398)
			(stroke
				(width 0.1524)
				(type default)
			)
			(layer "F.SilkS")
		)
		(fp_line
			(start -0.508 -0.9398)
			(end -0.508 0.9398)
			(stroke
				(width 0.1524)
				(type default)
			)
			(layer "F.SilkS")
		)
		(fp_rect
			(start -0.508 0.9398)
			(end 0.508 -0.9398)
			(stroke
				(width 0)
				(type default)
			)
			(fill no)
			(layer "F.CrtYd")
		)
		(fp_rect
			(start -0.508 0.9398)
			(end 0.508 -0.9398)
			(stroke
				(width 0)
				(type default)
			)
			(fill no)
			(layer "F.Fab")
		)
		(pad "1" smd custom
			(at 0 -0.4445 180)
			(size 0.1397 0.1397)
			(layers "F.Cu" "F.Mask" "F.Paste")
			(net "PE_CLK_100M_DR7_1_R_N")
			(options
				(clearance outline)
				(anchor circle)
			)
			(primitives
				(gr_poly
					(pts
						(arc
							(start -0.1778 -0.2794)
							(mid -0.249642 -0.249642)
							(end -0.2794 -0.1778)
						)
						(arc
							(start -0.2794 0.1778)
							(mid -0.249642 0.249642)
							(end -0.1778 0.2794)
						)
						(arc
							(start 0.1778 0.2794)
							(mid 0.249642 0.249642)
							(end 0.2794 0.1778)
						)
						(arc
							(start 0.2794 -0.1778)
							(mid 0.249642 -0.249642)
							(end 0.1778 -0.2794)
						)
					)
					(width 0)
					(fill yes)
				)
			)
		)
		(pad "2" smd custom
			(at 0 0.4445 180)
			(size 0.1397 0.1397)
			(layers "F.Cu" "F.Mask" "F.Paste")
			(net "PE_CLK100M_DR7_1_N")
			(options
				(clearance outline)
				(anchor circle)
			)
			(primitives
				(gr_poly
					(pts
						(arc
							(start -0.1778 -0.2794)
							(mid -0.249642 -0.249642)
							(end -0.2794 -0.1778)
						)
						(arc
							(start -0.2794 0.1778)
							(mid -0.249642 0.249642)
							(end -0.1778 0.2794)
						)
						(arc
							(start 0.1778 0.2794)
							(mid 0.249642 0.249642)
							(end 0.2794 0.1778)
						)
						(arc
							(start 0.2794 -0.1778)
							(mid 0.249642 -0.249642)
							(end 0.1778 -0.2794)
						)
					)
					(width 0)
					(fill yes)
				)
			)
		)
	)
	(footprint ""
		(layer "F.Cu")
		(at 214.757 -191.897 -90)
		(property "Reference" "U12"
			(at 0 0 270)
			(layer "F.SilkS")
			(hide yes)
			(effects
				(font
					(size 1.27 1.27)
				)
			)
		)
		(property "Value" "P2003EVG-GP"
			(at 0 -11.1252 270)
			(unlocked yes)
			(layer "F.Fab")
			(hide yes)
			(effects
				(font
					(size 1.016 1.016)
					(thickness 0.1524)
				)
			)
		)
		(property "Device Type" "SOIC8H79"
			(at 0 -12.6492 270)
			(unlocked yes)
			(layer "F.Fab")
			(hide yes)
			(effects
				(font
					(size 1.016 1.016)
					(thickness 0.1524)
				)
			)
		)
		(duplicate_pad_numbers_are_jumpers no)
		(fp_line
			(start -2.6162 3.429)
			(end -2.6162 1.4732)
			(stroke
				(width 0.4064)
				(type default)
			)
			(layer "F.SilkS")
		)
		(fp_line
			(start -2.7432 1.4224)
			(end 2.1336 1.4224)
			(stroke
				(width 0.1524)
				(type default)
			)
			(layer "F.SilkS")
		)
		(fp_line
			(start 2.1336 1.4224)
			(end 2.1336 -1.4224)
			(stroke
				(width 0.1524)
				(type default)
			)
			(layer "F.SilkS")
		)
		(fp_line
			(start -2.2352 0)
			(end -2.7432 0.508)
			(stroke
				(width 0.1524)
				(type default)
			)
			(layer "F.SilkS")
		)
		(fp_line
			(start -2.7432 -0.508)
			(end -2.2352 0)
			(stroke
				(width 0.1524)
				(type default)
			)
			(layer "F.SilkS")
		)
		(fp_line
			(start -2.7432 -1.4224)
			(end -2.7432 1.4224)
			(stroke
				(width 0.1524)
				(type default)
			)
			(layer "F.SilkS")
		)
		(fp_line
			(start 2.1336 -1.4224)
			(end -2.7432 -1.4224)
			(stroke
				(width 0.1524)
				(type default)
			)
			(layer "F.SilkS")
		)
		(fp_poly
			(pts
				(xy 2.2098 -1.4224) (xy 2.2098 1.4224) (xy -2.2225 1.4224) (xy -2.2225 -1.4224)
			)
			(stroke
				(width 0)
				(type default)
			)
			(fill yes)
			(layer "F.SilkS")
		)
		(fp_rect
			(start -2.4511 2.9972)
			(end 2.4511 -2.9972)
			(stroke
				(width 0)
				(type default)
			)
			(fill no)
			(layer "F.CrtYd")
		)
		(fp_poly
			(pts
				(xy -2.8194 3.6322) (xy -2.8194 -3.6322) (xy 2.8194 -3.6322) (xy 2.8194 -2.2987) (xy 2.4511 -2.2987)
				(xy 2.4511 -2.9972) (xy -2.4511 -2.9972) (xy -2.4511 2.9972) (xy 2.4511 2.9972) (xy 2.4511 -2.286)
				(xy 2.8194 -2.286) (xy 2.8194 3.6322)
			)
			(stroke
				(width 0)
				(type default)
			)
			(fill no)
			(layer "F.CrtYd")
		)
		(fp_rect
			(start -2.8194 3.6322)
			(end 2.8194 -3.6322)
			(stroke
				(width 0)
				(type default)
			)
			(fill no)
			(layer "F.Fab")
		)
		(pad "1" smd rect
			(at -1.905 2.54 270)
			(size 0.635 1.651)
			(layers "F.Cu" "F.Mask" "F.Paste")
			(net "P12V")
		)
		(pad "2" smd rect
			(at -0.635 2.54 270)
			(size 0.635 1.651)
			(layers "F.Cu" "F.Mask" "F.Paste")
			(net "P12V")
		)
		(pad "3" smd rect
			(at 0.635 2.54 270)
			(size 0.635 1.651)
			(layers "F.Cu" "F.Mask" "F.Paste")
			(net "P12V")
		)
		(pad "4" smd rect
			(at 1.905 2.54 270)
			(size 0.635 1.651)
			(layers "F.Cu" "F.Mask" "F.Paste")
			(net "SW_SSD3_N")
		)
		(pad "5" smd rect
			(at 1.905 -2.54 270)
			(size 0.635 1.651)
			(layers "F.Cu" "F.Mask" "F.Paste")
			(net "P12V_SSD3")
		)
		(pad "6" smd rect
			(at 0.635 -2.54 270)
			(size 0.635 1.651)
			(layers "F.Cu" "F.Mask" "F.Paste")
			(net "P12V_SSD3")
		)
		(pad "7" smd rect
			(at -0.635 -2.54 270)
			(size 0.635 1.651)
			(layers "F.Cu" "F.Mask" "F.Paste")
			(net "P12V_SSD3")
		)
		(pad "8" smd rect
			(at -1.905 -2.54 270)
			(size 0.635 1.651)
			(layers "F.Cu" "F.Mask" "F.Paste")
			(net "P12V_SSD3")
		)
	)
	(footprint ""
		(layer "F.Cu")
		(at 92.837 -14.732 90)
		(property "Reference" "R387"
			(at 0 0 90)
			(layer "F.SilkS")
			(hide yes)
			(effects
				(font
					(size 1.27 1.27)
				)
			)
		)
		(property "Value" "10KR2F-2-GP"
			(at 0.064008 -3.993896 90)
			(unlocked yes)
			(layer "F.Fab")
			(hide yes)
			(effects
				(font
					(size 1.016 1.016)
					(thickness 0.1524)
				)
			)
		)
		(property "Device Type" "R402H16"
			(at 0.064008 -5.517896 90)
			(unlocked yes)
			(layer "F.Fab")
			(hide yes)
			(effects
				(font
					(size 1.016 1.016)
					(thickness 0.1524)
				)
			)
		)
		(duplicate_pad_numbers_are_jumpers no)
		(fp_line
			(start 0.508 -0.9398)
			(end -0.508 -0.9398)
			(stroke
				(width 0.1524)
				(type default)
			)
			(layer "F.SilkS")
		)
		(fp_line
			(start -0.508 -0.9398)
			(end -0.508 0.9398)
			(stroke
				(width 0.1524)
				(type default)
			)
			(layer "F.SilkS")
		)
		(fp_rect
			(start -0.508 0.9398)
			(end 0.508 -0.9398)
			(stroke
				(width 0)
				(type default)
			)
			(fill no)
			(layer "F.CrtYd")
		)
		(fp_rect
			(start -0.508 0.9398)
			(end 0.508 -0.9398)
			(stroke
				(width 0)
				(type default)
			)
			(fill no)
			(layer "F.Fab")
		)
		(pad "1" smd custom
			(at 0 -0.4445 90)
			(size 0.1397 0.1397)
			(layers "F.Cu" "F.Mask" "F.Paste")
			(net "P12V")
			(options
				(clearance outline)
				(anchor circle)
			)
			(primitives
				(gr_poly
					(pts
						(arc
							(start -0.1778 -0.2794)
							(mid -0.249642 -0.249642)
							(end -0.2794 -0.1778)
						)
						(arc
							(start -0.2794 0.1778)
							(mid -0.249642 0.249642)
							(end -0.1778 0.2794)
						)
						(arc
							(start 0.1778 0.2794)
							(mid 0.249642 0.249642)
							(end 0.2794 0.1778)
						)
						(arc
							(start 0.2794 -0.1778)
							(mid 0.249642 -0.249642)
							(end 0.1778 -0.2794)
						)
					)
					(width 0)
					(fill yes)
				)
			)
		)
		(pad "2" smd custom
			(at 0 0.4445 90)
			(size 0.1397 0.1397)
			(layers "F.Cu" "F.Mask" "F.Paste")
			(net "P12V_SENSE")
			(options
				(clearance outline)
				(anchor circle)
			)
			(primitives
				(gr_poly
					(pts
						(arc
							(start -0.1778 -0.2794)
							(mid -0.249642 -0.249642)
							(end -0.2794 -0.1778)
						)
						(arc
							(start -0.2794 0.1778)
							(mid -0.249642 0.249642)
							(end -0.1778 0.2794)
						)
						(arc
							(start 0.1778 0.2794)
							(mid 0.249642 0.249642)
							(end 0.2794 0.1778)
						)
						(arc
							(start 0.2794 -0.1778)
							(mid 0.249642 -0.249642)
							(end 0.1778 -0.2794)
						)
					)
					(width 0)
					(fill yes)
				)
			)
		)
	)
	(footprint ""
		(layer "F.Cu")
		(at 78.5622 -102.1842)
		(property "Reference" "R9973"
			(at 0 0 0)
			(layer "F.SilkS")
			(hide yes)
			(effects
				(font
					(size 1.27 1.27)
				)
			)
		)
		(property "Value" "470R2F-GP"
			(at 0.064008 -3.993896 0)
			(unlocked yes)
			(layer "F.Fab")
			(hide yes)
			(effects
				(font
					(size 1.016 1.016)
					(thickness 0.1524)
				)
			)
		)
		(property "Device Type" "R402H16"
			(at 0.064008 -5.517896 0)
			(unlocked yes)
			(layer "F.Fab")
			(hide yes)
			(effects
				(font
					(size 1.016 1.016)
					(thickness 0.1524)
				)
			)
		)
		(duplicate_pad_numbers_are_jumpers no)
		(fp_line
			(start -0.508 -0.9398)
			(end -0.508 0.9398)
			(stroke
				(width 0.1524)
				(type default)
			)
			(layer "F.SilkS")
		)
		(fp_line
			(start 0.508 -0.9398)
			(end -0.508 -0.9398)
			(stroke
				(width 0.1524)
				(type default)
			)
			(layer "F.SilkS")
		)
		(fp_rect
			(start -0.508 0.9398)
			(end 0.508 -0.9398)
			(stroke
				(width 0)
				(type default)
			)
			(fill no)
			(layer "F.CrtYd")
		)
		(fp_rect
			(start -0.508 0.9398)
			(end 0.508 -0.9398)
			(stroke
				(width 0)
				(type default)
			)
			(fill no)
			(layer "F.Fab")
		)
		(pad "1" smd custom
			(at 0 -0.4445)
			(size 0.1397 0.1397)
			(layers "F.Cu" "F.Mask" "F.Paste")
			(net "VDD_DIFF_4")
			(options
				(clearance outline)
				(anchor circle)
			)
			(primitives
				(gr_poly
					(pts
						(arc
							(start -0.1778 -0.2794)
							(mid -0.249642 -0.249642)
							(end -0.2794 -0.1778)
						)
						(arc
							(start -0.2794 0.1778)
							(mid -0.249642 0.249642)
							(end -0.1778 0.2794)
						)
						(arc
							(start 0.1778 0.2794)
							(mid 0.249642 0.249642)
							(end 0.2794 0.1778)
						)
						(arc
							(start 0.2794 -0.1778)
							(mid 0.249642 -0.249642)
							(end 0.1778 -0.2794)
						)
					)
					(width 0)
					(fill yes)
				)
			)
		)
		(pad "2" smd custom
			(at 0 0.4445)
			(size 0.1397 0.1397)
			(layers "F.Cu" "F.Mask" "F.Paste")
			(net "PE_100M_CLK1_P")
			(options
				(clearance outline)
				(anchor circle)
			)
			(primitives
				(gr_poly
					(pts
						(arc
							(start -0.1778 -0.2794)
							(mid -0.249642 -0.249642)
							(end -0.2794 -0.1778)
						)
						(arc
							(start -0.2794 0.1778)
							(mid -0.249642 0.249642)
							(end -0.1778 0.2794)
						)
						(arc
							(start 0.1778 0.2794)
							(mid 0.249642 0.249642)
							(end 0.2794 0.1778)
						)
						(arc
							(start 0.2794 -0.1778)
							(mid 0.249642 -0.249642)
							(end 0.1778 -0.2794)
						)
					)
					(width 0)
					(fill yes)
				)
			)
		)
	)
	(footprint ""
		(layer "F.Cu")
		(at 97.155 -318.643)
		(property "Reference" "R9601"
			(at 0 0 0)
			(layer "F.SilkS")
			(hide yes)
			(effects
				(font
					(size 1.27 1.27)
				)
			)
		)
		(property "Value" "10R2F-L-GP"
			(at 0.064008 -3.993896 0)
			(unlocked yes)
			(layer "F.Fab")
			(hide yes)
			(effects
				(font
					(size 1.016 1.016)
					(thickness 0.1524)
				)
			)
		)
		(property "Device Type" "R402H14"
			(at 0.064008 -5.517896 0)
			(unlocked yes)
			(layer "F.Fab")
			(hide yes)
			(effects
				(font
					(size 1.016 1.016)
					(thickness 0.1524)
				)
			)
		)
		(duplicate_pad_numbers_are_jumpers no)
		(fp_line
			(start -0.508 -0.9398)
			(end -0.508 0.9398)
			(stroke
				(width 0.1524)
				(type default)
			)
			(layer "F.SilkS")
		)
		(fp_line
			(start 0.508 -0.9398)
			(end -0.508 -0.9398)
			(stroke
				(width 0.1524)
				(type default)
			)
			(layer "F.SilkS")
		)
		(fp_rect
			(start -0.508 0.9398)
			(end 0.508 -0.9398)
			(stroke
				(width 0)
				(type default)
			)
			(fill no)
			(layer "F.CrtYd")
		)
		(fp_rect
			(start -0.508 0.9398)
			(end 0.508 -0.9398)
			(stroke
				(width 0)
				(type default)
			)
			(fill no)
			(layer "F.Fab")
		)
		(pad "1" smd custom
			(at 0 -0.4445)
			(size 0.1397 0.1397)
			(layers "F.Cu" "F.Mask" "F.Paste")
			(net "SSD6_CLK0_OE_N")
			(options
				(clearance outline)
				(anchor circle)
			)
			(primitives
				(gr_poly
					(pts
						(arc
							(start -0.1778 -0.2794)
							(mid -0.249642 -0.249642)
							(end -0.2794 -0.1778)
						)
						(arc
							(start -0.2794 0.1778)
							(mid -0.249642 0.249642)
							(end -0.1778 0.2794)
						)
						(arc
							(start 0.1778 0.2794)
							(mid 0.249642 0.249642)
							(end 0.2794 0.1778)
						)
						(arc
							(start 0.2794 -0.1778)
							(mid 0.249642 -0.249642)
							(end 0.1778 -0.2794)
						)
					)
					(width 0)
					(fill yes)
				)
			)
		)
		(pad "2" smd custom
			(at 0 0.4445)
			(size 0.1397 0.1397)
			(layers "F.Cu" "F.Mask" "F.Paste")
			(net "SSD6_CLK0_OE_R_N")
			(options
				(clearance outline)
				(anchor circle)
			)
			(primitives
				(gr_poly
					(pts
						(arc
							(start -0.1778 -0.2794)
							(mid -0.249642 -0.249642)
							(end -0.2794 -0.1778)
						)
						(arc
							(start -0.2794 0.1778)
							(mid -0.249642 0.249642)
							(end -0.1778 0.2794)
						)
						(arc
							(start 0.1778 0.2794)
							(mid 0.249642 0.249642)
							(end 0.2794 0.1778)
						)
						(arc
							(start 0.2794 -0.1778)
							(mid 0.249642 -0.249642)
							(end 0.1778 -0.2794)
						)
					)
					(width 0)
					(fill yes)
				)
			)
		)
	)
	(footprint ""
		(layer "F.Cu")
		(at 89.662 -88.138 180)
		(property "Reference" "R9607"
			(at 0 0 180)
			(layer "F.SilkS")
			(hide yes)
			(effects
				(font
					(size 1.27 1.27)
				)
			)
		)
		(property "Value" "10R2F-L-GP"
			(at 0.064008 -3.993896 180)
			(unlocked yes)
			(layer "F.Fab")
			(hide yes)
			(effects
				(font
					(size 1.016 1.016)
					(thickness 0.1524)
				)
			)
		)
		(property "Device Type" "R402H14"
			(at 0.064008 -5.517896 180)
			(unlocked yes)
			(layer "F.Fab")
			(hide yes)
			(effects
				(font
					(size 1.016 1.016)
					(thickness 0.1524)
				)
			)
		)
		(duplicate_pad_numbers_are_jumpers no)
		(fp_line
			(start 0.508 -0.9398)
			(end -0.508 -0.9398)
			(stroke
				(width 0.1524)
				(type default)
			)
			(layer "F.SilkS")
		)
		(fp_line
			(start -0.508 -0.9398)
			(end -0.508 0.9398)
			(stroke
				(width 0.1524)
				(type default)
			)
			(layer "F.SilkS")
		)
		(fp_rect
			(start -0.508 0.9398)
			(end 0.508 -0.9398)
			(stroke
				(width 0)
				(type default)
			)
			(fill no)
			(layer "F.CrtYd")
		)
		(fp_rect
			(start -0.508 0.9398)
			(end 0.508 -0.9398)
			(stroke
				(width 0)
				(type default)
			)
			(fill no)
			(layer "F.Fab")
		)
		(pad "1" smd custom
			(at 0 -0.4445 180)
			(size 0.1397 0.1397)
			(layers "F.Cu" "F.Mask" "F.Paste")
			(net "SSD9_CLK0_OE_N")
			(options
				(clearance outline)
				(anchor circle)
			)
			(primitives
				(gr_poly
					(pts
						(arc
							(start -0.1778 -0.2794)
							(mid -0.249642 -0.249642)
							(end -0.2794 -0.1778)
						)
						(arc
							(start -0.2794 0.1778)
							(mid -0.249642 0.249642)
							(end -0.1778 0.2794)
						)
						(arc
							(start 0.1778 0.2794)
							(mid 0.249642 0.249642)
							(end 0.2794 0.1778)
						)
						(arc
							(start 0.2794 -0.1778)
							(mid 0.249642 -0.249642)
							(end 0.1778 -0.2794)
						)
					)
					(width 0)
					(fill yes)
				)
			)
		)
		(pad "2" smd custom
			(at 0 0.4445 180)
			(size 0.1397 0.1397)
			(layers "F.Cu" "F.Mask" "F.Paste")
			(net "SSD9_CLK0_OE_R_N")
			(options
				(clearance outline)
				(anchor circle)
			)
			(primitives
				(gr_poly
					(pts
						(arc
							(start -0.1778 -0.2794)
							(mid -0.249642 -0.249642)
							(end -0.2794 -0.1778)
						)
						(arc
							(start -0.2794 0.1778)
							(mid -0.249642 0.249642)
							(end -0.1778 0.2794)
						)
						(arc
							(start 0.1778 0.2794)
							(mid 0.249642 0.249642)
							(end 0.2794 0.1778)
						)
						(arc
							(start 0.2794 -0.1778)
							(mid 0.249642 -0.249642)
							(end 0.1778 -0.2794)
						)
					)
					(width 0)
					(fill yes)
				)
			)
		)
	)
)
